# T6G (Grand Teton) — schematic netlist excerpt (pin names and nets, part order shuffled) for the footprints in the layout excerpt that follows; sources: Cadence DE-HDL packaged netlist, KiCad conversion of 04192023_DAF0TMB3IC0_F0TG_MB_C_brd_V02_OCP.brd

PR78  Q_RES  8.87K 1% EMPTY  pkg 0402LF  page 201 : A = PVDDCR_CPU1_P0_LSET1 ; B = GND

Q8  MOSFET_DUAL_6P  2N7002KDW IC  pkg SOT363XD  page 187
  S1  = GND
  G1  = CLR_CMOS
  D2  = BAT_LDO_EN
  S2  = GND
  G2  = CLR_CMOS
  D1  = CLR_CMOS_N

(kicad_pcb
	(version 20260206)
	(generator "pcbnew")
	(generator_version "10.0")
	(general
		(thickness 1.6)
		(legacy_teardrops no)
	)
	(paper "A4")
	(title_block
		(title "04192023_DAF0TMB3IC0_F0TG_MB_C_brd_V02_OCP.brd")
		(comment 1 "Grand Teton / footprints 1863-1864 of 8354")
	)
	(layers
		(0 "F.Cu" signal "TOP")
		(4 "In1.Cu" signal "GND")
		(6 "In2.Cu" signal "IN1")
		(8 "In3.Cu" signal "GND1")
		(10 "In4.Cu" signal "IN2")
		(12 "In5.Cu" signal "GND2")
		(14 "In6.Cu" signal "IN3")
		(16 "In7.Cu" signal "GND3")
		(18 "In8.Cu" signal "VCC")
		(20 "In9.Cu" signal "VCC1")
		(22 "In10.Cu" signal "GND4")
		(24 "In11.Cu" signal "IN4")
		(26 "In12.Cu" signal "GND5")
		(28 "In13.Cu" signal "IN5")
		(30 "In14.Cu" signal "GND6")
		(32 "In15.Cu" signal "IN6")
		(34 "In16.Cu" signal "GND7")
		(2 "B.Cu" signal "BOTTOM")
		(9 "F.Adhes" user "F.Adhesive")
		(11 "B.Adhes" user "B.Adhesive")
		(13 "F.Paste" user "Package Geometry/Pastemask Top")
		(15 "B.Paste" user "Package Geometry/Pastemask Bottom")
		(5 "F.SilkS" user "Ref Des/Silkscreen Top")
		(7 "B.SilkS" user "Ref Des/Silkscreen Bottom")
		(1 "F.Mask" user "Board Geometry/Soldermask Top")
		(3 "B.Mask" user "Board Geometry/Soldermask Bottom")
		(17 "Dwgs.User" user "User.Drawings")
		(19 "Cmts.User" user "User.Comments")
		(21 "Eco1.User" user "User.Eco1")
		(23 "Eco2.User" user "User.Eco2")
		(25 "Edge.Cuts" user "Board Geometry/Outline")
		(27 "Margin" user)
		(31 "F.CrtYd" user "Package Geometry/Place Bound Top")
		(29 "B.CrtYd" user "Package Geometry/Place Bound Bottom")
		(35 "F.Fab" user "Ref Des/Assembly Top")
		(33 "B.Fab" user "Ref Des/Assembly Bottom")
	)
	(footprint ""
		(layer "F.Cu")
		(at 333.754476 -340.185248)
		(property "Reference" "PR78"
			(at 0 0 0)
			(layer "F.SilkS")
			(hide yes)
			(effects
				(font
					(size 1.27 1.27)
				)
			)
		)
		(property "Value" ""
			(at 0 0 0)
			(layer "F.Fab")
			(effects
				(font
					(size 1.27 1.27)
				)
			)
		)
		(duplicate_pad_numbers_are_jumpers no)
		(fp_line
			(start -0.7874 -0.4064)
			(end 0.7874 -0.4064)
			(stroke
				(width 0.1524)
				(type default)
			)
			(layer "F.SilkS")
		)
		(fp_line
			(start -0.7874 0.4064)
			(end -0.7874 -0.4064)
			(stroke
				(width 0.1524)
				(type default)
			)
			(layer "F.SilkS")
		)
		(fp_line
			(start 0.7874 -0.4064)
			(end 0.7874 0.4064)
			(stroke
				(width 0.1524)
				(type default)
			)
			(layer "F.SilkS")
		)
		(fp_line
			(start 0.7874 0.4064)
			(end -0.7874 0.4064)
			(stroke
				(width 0.1524)
				(type default)
			)
			(layer "F.SilkS")
		)
		(fp_line
			(start -0.67945 -0.305054)
			(end -0.12065 -0.305054)
			(stroke
				(width 0.1)
				(type default)
			)
			(layer "F.Fab")
		)
		(fp_line
			(start -0.67945 0.3048)
			(end -0.67945 -0.305054)
			(stroke
				(width 0.1)
				(type default)
			)
			(layer "F.Fab")
		)
		(fp_line
			(start -0.12065 -0.305054)
			(end -0.12065 -0.2794)
			(stroke
				(width 0.1)
				(type default)
			)
			(layer "F.Fab")
		)
		(fp_line
			(start -0.12065 -0.2794)
			(end 0.12065 -0.2794)
			(stroke
				(width 0.1)
				(type default)
			)
			(layer "F.Fab")
		)
		(fp_line
			(start -0.12065 0.2794)
			(end -0.12065 0.3048)
			(stroke
				(width 0.1)
				(type default)
			)
			(layer "F.Fab")
		)
		(fp_line
			(start -0.12065 0.3048)
			(end -0.67945 0.3048)
			(stroke
				(width 0.1)
				(type default)
			)
			(layer "F.Fab")
		)
		(fp_line
			(start 0.120396 0.2794)
			(end -0.12065 0.2794)
			(stroke
				(width 0.1)
				(type default)
			)
			(layer "F.Fab")
		)
		(fp_line
			(start 0.120396 0.3048)
			(end 0.120396 0.2794)
			(stroke
				(width 0.1)
				(type default)
			)
			(layer "F.Fab")
		)
		(fp_line
			(start 0.12065 -0.3048)
			(end 0.67945 -0.3048)
			(stroke
				(width 0.1)
				(type default)
			)
			(layer "F.Fab")
		)
		(fp_line
			(start 0.12065 -0.2794)
			(end 0.12065 -0.3048)
			(stroke
				(width 0.1)
				(type default)
			)
			(layer "F.Fab")
		)
		(fp_line
			(start 0.67945 -0.3048)
			(end 0.67945 0.3048)
			(stroke
				(width 0.1)
				(type default)
			)
			(layer "F.Fab")
		)
		(fp_line
			(start 0.67945 0.3048)
			(end 0.120396 0.3048)
			(stroke
				(width 0.1)
				(type default)
			)
			(layer "F.Fab")
		)
		(pad "1" smd circle
			(at -0.40005 0)
			(size 0 0)
			(layers "F.Cu" "F.Mask" "F.Paste")
			(net "PVDDCR_CPU1_P0_LSET1")
		)
		(pad "2" smd circle
			(at 0.40005 0)
			(size 0 0)
			(layers "F.Cu" "F.Mask" "F.Paste")
			(net "GND")
		)
	)
	(footprint ""
		(layer "F.Cu")
		(at 301.221902 -20.04695 -90)
		(property "Reference" "Q8"
			(at 1.510792 -2.157222 90)
			(unlocked yes)
			(layer "F.SilkS")
			(effects
				(font
					(size 0.7874 0.5842)
					(thickness 0.1524)
				)
				(justify left)
			)
		)
		(property "Value" ""
			(at 0 0 270)
			(layer "F.Fab")
			(effects
				(font
					(size 1.27 1.27)
				)
			)
		)
		(duplicate_pad_numbers_are_jumpers no)
		(fp_line
			(start -1.332738 1.100074)
			(end -1.332738 -1.100074)
			(stroke
				(width 0.1524)
				(type default)
			)
			(layer "F.SilkS")
		)
		(fp_line
			(start 1.332738 1.100074)
			(end -1.332738 1.100074)
			(stroke
				(width 0.1524)
				(type default)
			)
			(layer "F.SilkS")
		)
		(fp_line
			(start 0 -0.541274)
			(end 0.4826 -1.100074)
			(stroke
				(width 0.1524)
				(type default)
			)
			(layer "F.SilkS")
		)
		(fp_line
			(start -1.332738 -1.100074)
			(end -0.4826 -1.100074)
			(stroke
				(width 0.1524)
				(type default)
			)
			(layer "F.SilkS")
		)
		(fp_line
			(start -0.4826 -1.100074)
			(end 0 -0.541274)
			(stroke
				(width 0.1524)
				(type default)
			)
			(layer "F.SilkS")
		)
		(fp_line
			(start 0.4826 -1.100074)
			(end 1.332738 -1.100074)
			(stroke
				(width 0.1524)
				(type default)
			)
			(layer "F.SilkS")
		)
		(fp_line
			(start 1.332738 -1.100074)
			(end 1.332738 1.100074)
			(stroke
				(width 0.1524)
				(type default)
			)
			(layer "F.SilkS")
		)
		(fp_poly
			(pts
				(xy -0.983742 -1.228852) (xy -1.33477 -1.930908) (xy -0.632714 -1.930908)
			)
			(stroke
				(width 0)
				(type default)
			)
			(fill yes)
			(layer "F.SilkS")
		)
		(fp_line
			(start -0.674878 1.100074)
			(end -0.674878 -1.100074)
			(stroke
				(width 0.1)
				(type default)
			)
			(layer "F.Fab")
		)
		(fp_line
			(start 0.674878 1.100074)
			(end -0.674878 1.100074)
			(stroke
				(width 0.1)
				(type default)
			)
			(layer "F.Fab")
		)
		(fp_line
			(start -0.674878 -1.100074)
			(end 0.674878 -1.100074)
			(stroke
				(width 0.1)
				(type default)
			)
			(layer "F.Fab")
		)
		(fp_line
			(start 0.674878 -1.100074)
			(end 0.674878 1.100074)
			(stroke
				(width 0.1)
				(type default)
			)
			(layer "F.Fab")
		)
		(fp_poly
			(pts
				(xy -2.2352 -0.298958) (xy -2.2352 -1.001014) (xy -1.533144 -0.649986)
			)
			(stroke
				(width 0)
				(type default)
			)
			(fill yes)
			(layer "F.Fab")
		)
		(pad "1" smd rect
			(at -0.94996 -0.649986)
			(size 0.4318 0.508)
			(layers "F.Cu" "F.Mask" "F.Paste")
			(net "GND")
		)
		(pad "2" smd rect
			(at -0.94996 0)
			(size 0.4318 0.508)
			(layers "F.Cu" "F.Mask" "F.Paste")
			(net "CLR_CMOS")
		)
		(pad "3" smd rect
			(at -0.94996 0.649986)
			(size 0.4318 0.508)
			(layers "F.Cu" "F.Mask" "F.Paste")
			(net "BAT_LDO_EN")
		)
		(pad "4" smd rect
			(at 0.94996 0.649986)
			(size 0.4318 0.508)
			(layers "F.Cu" "F.Mask" "F.Paste")
			(net "GND")
		)
		(pad "5" smd rect
			(at 0.94996 0)
			(size 0.4318 0.508)
			(layers "F.Cu" "F.Mask" "F.Paste")
			(net "CLR_CMOS")
		)
		(pad "6" smd rect
			(at 0.94996 -0.649986)
			(size 0.4318 0.508)
			(layers "F.Cu" "F.Mask" "F.Paste")
			(net "CLR_CMOS_N")
		)
	)
)
